# BASEBOARD_FAB2 (Tioga Pass) — schematic netlist excerpt (pin names and nets, part order shuffled) for the footprints in the layout excerpt that follows; sources: Cadence DE-HDL packaged netlist, KiCad conversion of Wiwynn_Tioga_Pass_MB.brd

C4C5  CAP  0.22UF 16V 10% X7R  pkg 0402  page 205 : A = P5V_STBY ; B = GND
C1D9  CAP_A  0.1UF 16V 10% X7R  pkg 0402V  page 200 : A = P12V_STBY ; B = AGND_HSC
R8E2  RES  1.00K 1% CHIP  pkg 0402  page 111 : A = XDP_SPI_PCH_MOSI_BOOT_HALT_N ; B = SPI_PCH_MOSI

(kicad_pcb
	(version 20260206)
	(generator "pcbnew")
	(generator_version "10.0")
	(general
		(thickness 1.6)
		(legacy_teardrops no)
	)
	(paper "A4")
	(title_block
		(title "Wiwynn_Tioga_Pass_MB.brd")
		(comment 1 "Tioga Pass / footprints 1951-1953 of 4770")
	)
	(layers
		(0 "F.Cu" signal "TOP")
		(4 "In1.Cu" signal "L2GND")
		(6 "In2.Cu" signal "L3")
		(8 "In3.Cu" signal "L4GND")
		(10 "In4.Cu" signal "L5")
		(12 "In5.Cu" signal "L6GND")
		(14 "In6.Cu" signal "L7VCC")
		(16 "In7.Cu" signal "L8VCC")
		(18 "In8.Cu" signal "L9GND")
		(20 "In9.Cu" signal "L10")
		(22 "In10.Cu" signal "L11GND")
		(24 "In11.Cu" signal "L12")
		(26 "In12.Cu" signal "L13GND")
		(2 "B.Cu" signal "BOTTOM")
		(9 "F.Adhes" user "F.Adhesive")
		(11 "B.Adhes" user "B.Adhesive")
		(13 "F.Paste" user "Package Geometry/Pastemask Top")
		(15 "B.Paste" user "Package Geometry/Pastemask Bottom")
		(5 "F.SilkS" user "Ref Des/Silkscreen Top")
		(7 "B.SilkS" user "Ref Des/Silkscreen Bottom")
		(1 "F.Mask" user "Board Geometry/Soldermask Top")
		(3 "B.Mask" user "Board Geometry/Soldermask Bottom")
		(17 "Dwgs.User" user "User.Drawings")
		(19 "Cmts.User" user "User.Comments")
		(21 "Eco1.User" user "User.Eco1")
		(23 "Eco2.User" user "User.Eco2")
		(25 "Edge.Cuts" user "Board Geometry/Outline")
		(27 "Margin" user)
		(31 "F.CrtYd" user "Package Geometry/Place Bound Top")
		(29 "B.CrtYd" user "Package Geometry/Place Bound Bottom")
		(35 "F.Fab" user "Ref Des/Assembly Top")
		(33 "B.Fab" user "Ref Des/Assembly Bottom")
	)
	(footprint ""
		(layer "F.Cu")
		(at 21.336 -81.79308)
		(property "Reference" "C1D9"
			(at 0 0 0)
			(layer "F.SilkS")
			(hide yes)
			(effects
				(font
					(size 1.27 1.27)
				)
			)
		)
		(property "Value" ""
			(at 0 0 0)
			(layer "F.Fab")
			(effects
				(font
					(size 1.27 1.27)
				)
			)
		)
		(duplicate_pad_numbers_are_jumpers no)
		(fp_poly
			(pts
				(xy 0.3048 -0.1016) (xy 0.3048 0.9906) (xy -0.3048 0.9906) (xy -0.3048 -0.1016)
			)
			(stroke
				(width 0)
				(type default)
			)
			(fill no)
			(layer "F.CrtYd")
		)
		(fp_line
			(start -0.3048 -0.1016)
			(end -0.3048 0.9906)
			(stroke
				(width 0.1)
				(type default)
			)
			(layer "F.Fab")
		)
		(fp_line
			(start -0.3048 0.9906)
			(end 0.3048 0.9906)
			(stroke
				(width 0.1)
				(type default)
			)
			(layer "F.Fab")
		)
		(fp_line
			(start 0.3048 -0.1016)
			(end -0.3048 -0.1016)
			(stroke
				(width 0.1)
				(type default)
			)
			(layer "F.Fab")
		)
		(fp_line
			(start 0.3048 0.9906)
			(end 0.3048 -0.1016)
			(stroke
				(width 0.1)
				(type default)
			)
			(layer "F.Fab")
		)
		(pad "1" smd rect
			(at 0 0)
			(size 0.508 0.508)
			(layers "F.Cu" "F.Mask" "F.Paste")
			(net "P12V_STBY")
		)
		(pad "2" smd rect
			(at 0 0.889)
			(size 0.508 0.508)
			(layers "F.Cu" "F.Mask" "F.Paste")
			(net "AGND_HSC")
		)
		(zone
			(layer "F.Cu")
			(hatch none 0.5)
			(connect_pads
				(clearance 0)
			)
			(min_thickness 0.25)
			(keepout
				(tracks allowed)
				(vias not_allowed)
				(pads allowed)
				(copperpour not_allowed)
				(footprints allowed)
			)
			(placement
				(enabled no)
				(sheetname "")
			)
			(fill
				(thermal_gap 0.5)
				(thermal_bridge_width 0.5)
				(island_removal_mode 0)
			)
			(polygon
				(pts
					(xy 21.082 -81.53908) (xy 21.59 -81.53908) (xy 21.59 -81.15808) (xy 21.082 -81.15808)
				)
			)
		)
		(zone
			(layer "F.Cu")
			(hatch none 0.5)
			(connect_pads
				(clearance 0)
			)
			(min_thickness 0.25)
			(keepout
				(tracks not_allowed)
				(vias allowed)
				(pads allowed)
				(copperpour not_allowed)
				(footprints allowed)
			)
			(placement
				(enabled no)
				(sheetname "")
			)
			(fill
				(thermal_gap 0.5)
				(thermal_bridge_width 0.5)
				(island_removal_mode 0)
			)
			(polygon
				(pts
					(xy 21.082 -81.15808) (xy 21.59 -81.15808) (xy 21.59 -81.53908) (xy 21.082 -81.53908)
				)
			)
		)
	)
	(footprint ""
		(layer "F.Cu")
		(at 198.039228 -93.861382 90)
		(property "Reference" "C4C5"
			(at 0 0 90)
			(layer "F.SilkS")
			(hide yes)
			(effects
				(font
					(size 1.27 1.27)
				)
			)
		)
		(property "Value" ""
			(at 0 0 90)
			(layer "F.Fab")
			(effects
				(font
					(size 1.27 1.27)
				)
			)
		)
		(duplicate_pad_numbers_are_jumpers no)
		(fp_rect
			(start 0.3048 0.9906)
			(end -0.3048 -0.1016)
			(stroke
				(width 0)
				(type default)
			)
			(fill no)
			(layer "F.CrtYd")
		)
		(fp_line
			(start 0.3048 -0.1016)
			(end -0.3048 -0.1016)
			(stroke
				(width 0.1)
				(type default)
			)
			(layer "F.Fab")
		)
		(fp_line
			(start -0.3048 -0.1016)
			(end -0.3048 0.9906)
			(stroke
				(width 0.1)
				(type default)
			)
			(layer "F.Fab")
		)
		(fp_line
			(start 0.3048 0.9906)
			(end 0.3048 -0.1016)
			(stroke
				(width 0.1)
				(type default)
			)
			(layer "F.Fab")
		)
		(fp_line
			(start -0.3048 0.9906)
			(end 0.3048 0.9906)
			(stroke
				(width 0.1)
				(type default)
			)
			(layer "F.Fab")
		)
		(pad "1" smd rect
			(at 0 0 90)
			(size 0.508 0.508)
			(layers "F.Cu" "F.Mask" "F.Paste")
			(net "P5V_STBY")
		)
		(pad "2" smd rect
			(at 0 0.889 90)
			(size 0.508 0.508)
			(layers "F.Cu" "F.Mask" "F.Paste")
			(net "GND")
		)
		(zone
			(layer "F.Cu")
			(hatch none 0.5)
			(connect_pads
				(clearance 0)
			)
			(min_thickness 0.25)
			(keepout
				(tracks not_allowed)
				(vias allowed)
				(pads allowed)
				(copperpour not_allowed)
				(footprints allowed)
			)
			(placement
				(enabled no)
				(sheetname "")
			)
			(fill
				(thermal_gap 0.5)
				(thermal_bridge_width 0.5)
				(island_removal_mode 0)
			)
			(polygon
				(pts
					(xy 198.674228 -94.115382) (xy 198.293228 -94.115382) (xy 198.293228 -93.607382) (xy 198.674228 -93.607382)
				)
			)
		)
		(zone
			(layer "F.Cu")
			(hatch none 0.5)
			(connect_pads
				(clearance 0)
			)
			(min_thickness 0.25)
			(keepout
				(tracks allowed)
				(vias not_allowed)
				(pads allowed)
				(copperpour not_allowed)
				(footprints allowed)
			)
			(placement
				(enabled no)
				(sheetname "")
			)
			(fill
				(thermal_gap 0.5)
				(thermal_bridge_width 0.5)
				(island_removal_mode 0)
			)
			(polygon
				(pts
					(xy 198.674228 -94.115382) (xy 198.293228 -94.115382) (xy 198.293228 -93.607382) (xy 198.674228 -93.607382)
				)
			)
		)
	)
	(footprint ""
		(layer "F.Cu")
		(at 406.197054 -64.298068)
		(property "Reference" "R8E2"
			(at 0 0 0)
			(layer "F.SilkS")
			(hide yes)
			(effects
				(font
					(size 1.27 1.27)
				)
			)
		)
		(property "Value" ""
			(at 0 0 0)
			(layer "F.Fab")
			(effects
				(font
					(size 1.27 1.27)
				)
			)
		)
		(duplicate_pad_numbers_are_jumpers no)
		(fp_poly
			(pts
				(xy -0.2794 -0.1016) (xy 0.2794 -0.1016) (xy 0.2794 0.9906) (xy -0.2794 0.9906)
			)
			(stroke
				(width 0)
				(type default)
			)
			(fill no)
			(layer "F.CrtYd")
		)
		(fp_line
			(start -0.2794 -0.1016)
			(end -0.2794 0.9906)
			(stroke
				(width 0.1)
				(type default)
			)
			(layer "F.Fab")
		)
		(fp_line
			(start -0.2794 0.9906)
			(end 0.2794 0.9906)
			(stroke
				(width 0.1)
				(type default)
			)
			(layer "F.Fab")
		)
		(fp_line
			(start 0.2794 -0.1016)
			(end -0.2794 -0.1016)
			(stroke
				(width 0.1)
				(type default)
			)
			(layer "F.Fab")
		)
		(fp_line
			(start 0.2794 0.9906)
			(end 0.2794 -0.1016)
			(stroke
				(width 0.1)
				(type default)
			)
			(layer "F.Fab")
		)
		(pad "1" smd rect
			(at 0 0)
			(size 0.508 0.508)
			(layers "F.Cu" "F.Mask" "F.Paste")
			(net "XDP_SPI_PCH_MOSI_BOOT_HALT_N")
		)
		(pad "2" smd rect
			(at 0 0.889)
			(size 0.508 0.508)
			(layers "F.Cu" "F.Mask" "F.Paste")
			(net "SPI_PCH_MOSI")
		)
		(zone
			(layer "F.Cu")
			(hatch none 0.5)
			(connect_pads
				(clearance 0)
			)
			(min_thickness 0.25)
			(keepout
				(tracks allowed)
				(vias not_allowed)
				(pads allowed)
				(copperpour not_allowed)
				(footprints allowed)
			)
			(placement
				(enabled no)
				(sheetname "")
			)
			(fill
				(thermal_gap 0.5)
				(thermal_bridge_width 0.5)
				(island_removal_mode 0)
			)
			(polygon
				(pts
					(xy 405.943054 -64.044068) (xy 406.451054 -64.044068) (xy 406.451054 -63.663068) (xy 405.943054 -63.663068)
				)
			)
		)
		(zone
			(layer "F.Cu")
			(hatch none 0.5)
			(connect_pads
				(clearance 0)
			)
			(min_thickness 0.25)
			(keepout
				(tracks not_allowed)
				(vias allowed)
				(pads allowed)
				(copperpour not_allowed)
				(footprints allowed)
			)
			(placement
				(enabled no)
				(sheetname "")
			)
			(fill
				(thermal_gap 0.5)
				(thermal_bridge_width 0.5)
				(island_removal_mode 0)
			)
			(polygon
				(pts
					(xy 405.943054 -63.663068) (xy 406.451054 -63.663068) (xy 406.451054 -64.044068) (xy 405.943054 -64.044068)
				)
			)
		)
	)
)
